# T6G (Grand Teton) — schematic netlist excerpt (pin names and nets, part order shuffled) for the footprints in the layout excerpt that follows; sources: Cadence DE-HDL packaged netlist, KiCad conversion of 04192023_DAF0TMB3IC0_F0TG_MB_C_brd_V02_OCP.brd

PU200  MAX15090BEWIT  MAX15090BEWI+T IC  pkg BGA28_0-5_3-525X2-065  page 140
  ISENSE  = P3V3_OCP_SENSE_2
  VCC  = P3V3_OCP_VCC_2
  IN_A3  = P3V3_AUX
  OUT_A4  = P3V3_OCP_V3_2_R
  IN_A5  = P3V3_AUX
  GATE  = P3V3_OCP_GATE_2
  CDLY  = GND
  CB  = P3V3_OCP_CB_2
  GND_B2  = GND
  IN_B3  = P3V3_AUX
  OUT_B4  = P3V3_OCP_V3_2_R
  IN_B5  = P3V3_AUX
  OUT_B6  = P3V3_OCP_V3_2_R
  \en#\  = GND
  GND_C1  = GND
  GND_C2  = GND
  IN_C3  = P3V3_AUX
  OUT_C4  = P3V3_OCP_V3_2_R
  IN_C5  = P3V3_AUX
  OUT_C6  = P3V3_OCP_V3_2_R
  \fault#\  = P3V3_OCP_FAULT_2
  REG  = P3V3_OCP_REG_2
  UV  = P3V3_OCP_UV_2
  OV  = P3V3_OCP_OV_2
  OUT_D4  = P3V3_OCP_V3_2_R
  IN_D5  = P3V3_AUX
  OUT_D6  = P3V3_OCP_V3_2_R
  PG  = P3V3_OCP_PWRGD_2

(kicad_pcb
	(version 20260206)
	(generator "pcbnew")
	(generator_version "10.0")
	(general
		(thickness 1.6)
		(legacy_teardrops no)
	)
	(paper "A4")
	(title_block
		(title "04192023_DAF0TMB3IC0_F0TG_MB_C_brd_V02_OCP.brd")
		(comment 1 "Grand Teton / footprints 3709-3709 of 8354")
	)
	(layers
		(0 "F.Cu" signal "TOP")
		(4 "In1.Cu" signal "GND")
		(6 "In2.Cu" signal "IN1")
		(8 "In3.Cu" signal "GND1")
		(10 "In4.Cu" signal "IN2")
		(12 "In5.Cu" signal "GND2")
		(14 "In6.Cu" signal "IN3")
		(16 "In7.Cu" signal "GND3")
		(18 "In8.Cu" signal "VCC")
		(20 "In9.Cu" signal "VCC1")
		(22 "In10.Cu" signal "GND4")
		(24 "In11.Cu" signal "IN4")
		(26 "In12.Cu" signal "GND5")
		(28 "In13.Cu" signal "IN5")
		(30 "In14.Cu" signal "GND6")
		(32 "In15.Cu" signal "IN6")
		(34 "In16.Cu" signal "GND7")
		(2 "B.Cu" signal "BOTTOM")
		(9 "F.Adhes" user "F.Adhesive")
		(11 "B.Adhes" user "B.Adhesive")
		(13 "F.Paste" user "Package Geometry/Pastemask Top")
		(15 "B.Paste" user "Package Geometry/Pastemask Bottom")
		(5 "F.SilkS" user "Ref Des/Silkscreen Top")
		(7 "B.SilkS" user "Ref Des/Silkscreen Bottom")
		(1 "F.Mask" user "Board Geometry/Soldermask Top")
		(3 "B.Mask" user "Board Geometry/Soldermask Bottom")
		(17 "Dwgs.User" user "User.Drawings")
		(19 "Cmts.User" user "User.Comments")
		(21 "Eco1.User" user "User.Eco1")
		(23 "Eco2.User" user "User.Eco2")
		(25 "Edge.Cuts" user "Board Geometry/Outline")
		(27 "Margin" user)
		(31 "F.CrtYd" user "Package Geometry/Place Bound Top")
		(29 "B.CrtYd" user "Package Geometry/Place Bound Bottom")
		(35 "F.Fab" user "Ref Des/Assembly Top")
		(33 "B.Fab" user "Ref Des/Assembly Bottom")
	)
	(footprint ""
		(layer "F.Cu")
		(at 91.45143 -58.33237 180)
		(property "Reference" "PU200"
			(at 2.957068 2.756662 0)
			(unlocked yes)
			(layer "F.SilkS")
			(effects
				(font
					(size 0.7874 0.5842)
					(thickness 0.1524)
				)
				(justify left)
			)
		)
		(property "Value" ""
			(at 0 0 180)
			(layer "F.Fab")
			(effects
				(font
					(size 1.27 1.27)
				)
			)
		)
		(duplicate_pad_numbers_are_jumpers no)
		(fp_line
			(start 1.774952 1.039876)
			(end 1.774952 -1.039876)
			(stroke
				(width 0.1524)
				(type default)
			)
			(layer "F.SilkS")
		)
		(fp_line
			(start 1.774952 -1.039876)
			(end -1.774952 -1.039876)
			(stroke
				(width 0.1524)
				(type default)
			)
			(layer "F.SilkS")
		)
		(fp_line
			(start -1.774952 1.039876)
			(end 1.774952 1.039876)
			(stroke
				(width 0.1524)
				(type default)
			)
			(layer "F.SilkS")
		)
		(fp_line
			(start -1.774952 -1.039876)
			(end -1.774952 1.039876)
			(stroke
				(width 0.1524)
				(type default)
			)
			(layer "F.SilkS")
		)
		(fp_poly
			(pts
				(xy -0.999998 -1.801876) (xy -0.999998 -1.039876) (xy -1.769872 -1.039876) (xy -1.769872 -0.249936)
				(xy -2.531872 -0.249936) (xy -2.531872 -1.801876)
			)
			(stroke
				(width 0)
				(type default)
			)
			(fill yes)
			(layer "F.SilkS")
		)
		(fp_line
			(start 1.769872 1.039876)
			(end 1.769872 -1.039876)
			(stroke
				(width 0.1)
				(type default)
			)
			(layer "F.Fab")
		)
		(fp_line
			(start 1.769872 -1.039876)
			(end -1.769872 -1.039876)
			(stroke
				(width 0.1)
				(type default)
			)
			(layer "F.Fab")
		)
		(fp_line
			(start -1.769872 1.039876)
			(end 1.769872 1.039876)
			(stroke
				(width 0.1)
				(type default)
			)
			(layer "F.Fab")
		)
		(fp_line
			(start -1.769872 -1.039876)
			(end -1.769872 1.039876)
			(stroke
				(width 0.1)
				(type default)
			)
			(layer "F.Fab")
		)
		(fp_poly
			(pts
				(xy -1.769872 -1.039876) (xy -0.999998 -1.039876) (xy -0.999998 -1.801876) (xy -2.531872 -1.801876)
				(xy -2.531872 -0.249936) (xy -1.769872 -0.249936)
			)
			(stroke
				(width 0)
				(type default)
			)
			(fill yes)
			(layer "F.Fab")
		)
		(pad "A1" smd circle
			(at -1.500124 -0.750062 180)
			(size 0.2286 0.2286)
			(layers "F.Cu" "F.Mask" "F.Paste")
			(net "P3V3_OCP_SENSE_2")
		)
		(pad "A2" smd circle
			(at -0.999998 -0.750062 180)
			(size 0.2286 0.2286)
			(layers "F.Cu" "F.Mask" "F.Paste")
			(net "P3V3_OCP_VCC_2")
		)
		(pad "A3" smd circle
			(at -0.499872 -0.750062 180)
			(size 0.2286 0.2286)
			(layers "F.Cu" "F.Mask" "F.Paste")
			(net "P3V3_AUX")
		)
		(pad "A4" smd circle
			(at 0 -0.750062 180)
			(size 0.2286 0.2286)
			(layers "F.Cu" "F.Mask" "F.Paste")
			(net "P3V3_OCP_V3_2_R")
		)
		(pad "A5" smd circle
			(at 0.499872 -0.750062 180)
			(size 0.2286 0.2286)
			(layers "F.Cu" "F.Mask" "F.Paste")
			(net "P3V3_AUX")
		)
		(pad "A6" smd circle
			(at 0.999998 -0.750062 180)
			(size 0.2286 0.2286)
			(layers "F.Cu" "F.Mask" "F.Paste")
			(net "P3V3_OCP_GATE_2")
		)
		(pad "A7" smd circle
			(at 1.500124 -0.750062 180)
			(size 0.2286 0.2286)
			(layers "F.Cu" "F.Mask" "F.Paste")
			(net "GND")
		)
		(pad "B1" smd circle
			(at -1.500124 -0.249936 180)
			(size 0.2286 0.2286)
			(layers "F.Cu" "F.Mask" "F.Paste")
			(net "P3V3_OCP_CB_2")
		)
		(pad "B2" smd circle
			(at -0.999998 -0.249936 180)
			(size 0.2286 0.2286)
			(layers "F.Cu" "F.Mask" "F.Paste")
			(net "GND")
		)
		(pad "B3" smd circle
			(at -0.499872 -0.249936 180)
			(size 0.2286 0.2286)
			(layers "F.Cu" "F.Mask" "F.Paste")
			(net "P3V3_AUX")
		)
		(pad "B4" smd circle
			(at 0 -0.249936 180)
			(size 0.2286 0.2286)
			(layers "F.Cu" "F.Mask" "F.Paste")
			(net "P3V3_OCP_V3_2_R")
		)
		(pad "B5" smd circle
			(at 0.499872 -0.249936 180)
			(size 0.2286 0.2286)
			(layers "F.Cu" "F.Mask" "F.Paste")
			(net "P3V3_AUX")
		)
		(pad "B6" smd circle
			(at 0.999998 -0.249936 180)
			(size 0.2286 0.2286)
			(layers "F.Cu" "F.Mask" "F.Paste")
			(net "P3V3_OCP_V3_2_R")
		)
		(pad "B7" smd circle
			(at 1.500124 -0.249936 180)
			(size 0.2286 0.2286)
			(layers "F.Cu" "F.Mask" "F.Paste")
			(net "GND")
		)
		(pad "C1" smd circle
			(at -1.500124 0.249936 180)
			(size 0.2286 0.2286)
			(layers "F.Cu" "F.Mask" "F.Paste")
			(net "GND")
		)
		(pad "C2" smd circle
			(at -0.999998 0.249936 180)
			(size 0.2286 0.2286)
			(layers "F.Cu" "F.Mask" "F.Paste")
			(net "GND")
		)
		(pad "C3" smd circle
			(at -0.499872 0.249936 180)
			(size 0.2286 0.2286)
			(layers "F.Cu" "F.Mask" "F.Paste")
			(net "P3V3_AUX")
		)
		(pad "C4" smd circle
			(at 0 0.249936 180)
			(size 0.2286 0.2286)
			(layers "F.Cu" "F.Mask" "F.Paste")
			(net "P3V3_OCP_V3_2_R")
		)
		(pad "C5" smd circle
			(at 0.499872 0.249936 180)
			(size 0.2286 0.2286)
			(layers "F.Cu" "F.Mask" "F.Paste")
			(net "P3V3_AUX")
		)
		(pad "C6" smd circle
			(at 0.999998 0.249936 180)
			(size 0.2286 0.2286)
			(layers "F.Cu" "F.Mask" "F.Paste")
			(net "P3V3_OCP_V3_2_R")
		)
		(pad "C7" smd circle
			(at 1.500124 0.249936 180)
			(size 0.2286 0.2286)
			(layers "F.Cu" "F.Mask" "F.Paste")
			(net "P3V3_OCP_FAULT_2")
		)
		(pad "D1" smd circle
			(at -1.500124 0.750062 180)
			(size 0.2286 0.2286)
			(layers "F.Cu" "F.Mask" "F.Paste")
			(net "P3V3_OCP_REG_2")
		)
		(pad "D2" smd circle
			(at -0.999998 0.750062 180)
			(size 0.2286 0.2286)
			(layers "F.Cu" "F.Mask" "F.Paste")
			(net "P3V3_OCP_UV_2")
		)
		(pad "D3" smd circle
			(at -0.499872 0.750062 180)
			(size 0.2286 0.2286)
			(layers "F.Cu" "F.Mask" "F.Paste")
			(net "P3V3_OCP_OV_2")
		)
		(pad "D4" smd circle
			(at 0 0.750062 180)
			(size 0.2286 0.2286)
			(layers "F.Cu" "F.Mask" "F.Paste")
			(net "P3V3_OCP_V3_2_R")
		)
		(pad "D5" smd circle
			(at 0.499872 0.750062 180)
			(size 0.2286 0.2286)
			(layers "F.Cu" "F.Mask" "F.Paste")
			(net "P3V3_AUX")
		)
		(pad "D6" smd circle
			(at 0.999998 0.750062 180)
			(size 0.2286 0.2286)
			(layers "F.Cu" "F.Mask" "F.Paste")
			(net "P3V3_OCP_V3_2_R")
		)
		(pad "D7" smd circle
			(at 1.500124 0.750062 180)
			(size 0.2286 0.2286)
			(layers "F.Cu" "F.Mask" "F.Paste")
			(net "P3V3_OCP_PWRGD_2")
		)
	)
)
